# S9S_MB_2U (Grand Teton) — schematic netlist excerpt (pin names and nets, part order shuffled) for the footprints in the layout excerpt that follows; sources: Cadence DE-HDL packaged netlist, KiCad conversion of 03242023_DA0F0TMBIJ0_F0T_Motherboard_J_brd_V01_OCP.brd

R1311  Q_RES  10K 1% CHIP  pkg 0402LF  page 200 : A = FM_XTAL_INPUT_FREQUENCY_0_MGPIO ; B = GND
R4288  Q_RES  1K 1% EMPTY  pkg 0402LF  page 169 : A = FM_USB3_1_SWA ; B = GND

(kicad_pcb
	(version 20260206)
	(generator "pcbnew")
	(generator_version "10.0")
	(general
		(thickness 1.6)
		(legacy_teardrops no)
	)
	(paper "A4")
	(title_block
		(title "03242023_DA0F0TMBIJ0_F0T_Motherboard_J_brd_V01_OCP.brd")
		(comment 1 "Grand Teton / footprints 4374-4375 of 6105")
	)
	(layers
		(0 "F.Cu" signal "TOP")
		(4 "In1.Cu" signal "GND")
		(6 "In2.Cu" signal "IN1")
		(8 "In3.Cu" signal "GND1")
		(10 "In4.Cu" signal "IN2")
		(12 "In5.Cu" signal "GND2")
		(14 "In6.Cu" signal "IN3")
		(16 "In7.Cu" signal "GND3")
		(18 "In8.Cu" signal "VCC")
		(20 "In9.Cu" signal "VCC1")
		(22 "In10.Cu" signal "GND4")
		(24 "In11.Cu" signal "IN4")
		(26 "In12.Cu" signal "GND5")
		(28 "In13.Cu" signal "IN5")
		(30 "In14.Cu" signal "GND6")
		(32 "In15.Cu" signal "IN6")
		(34 "In16.Cu" signal "GND7")
		(2 "B.Cu" signal "BOTTOM")
		(9 "F.Adhes" user "F.Adhesive")
		(11 "B.Adhes" user "B.Adhesive")
		(13 "F.Paste" user "Package Geometry/Pastemask Top")
		(15 "B.Paste" user "Package Geometry/Pastemask Bottom")
		(5 "F.SilkS" user "Ref Des/Silkscreen Top")
		(7 "B.SilkS" user "Ref Des/Silkscreen Bottom")
		(1 "F.Mask" user "Board Geometry/Soldermask Top")
		(3 "B.Mask" user "Board Geometry/Soldermask Bottom")
		(17 "Dwgs.User" user "User.Drawings")
		(19 "Cmts.User" user "User.Comments")
		(21 "Eco1.User" user "User.Eco1")
		(23 "Eco2.User" user "User.Eco2")
		(25 "Edge.Cuts" user "Board Geometry/Outline")
		(27 "Margin" user)
		(31 "F.CrtYd" user "Package Geometry/Place Bound Top")
		(29 "B.CrtYd" user "Package Geometry/Place Bound Bottom")
		(35 "F.Fab" user "Ref Des/Assembly Top")
		(33 "B.Fab" user "Ref Des/Assembly Bottom")
	)
	(footprint ""
		(layer "B.Cu")
		(at 339.58022 -31.929578 90)
		(property "Reference" "R1311"
			(at 0 0 90)
			(layer "B.SilkS")
			(hide yes)
			(effects
				(font
					(size 1.27 1.27)
				)
				(justify mirror)
			)
		)
		(property "Value" ""
			(at 0 0 90)
			(layer "B.Fab")
			(effects
				(font
					(size 1.27 1.27)
				)
				(justify mirror)
			)
		)
		(duplicate_pad_numbers_are_jumpers no)
		(fp_line
			(start 0.7874 -0.4064)
			(end -0.7874 -0.4064)
			(stroke
				(width 0.1524)
				(type default)
			)
			(layer "B.SilkS")
		)
		(fp_line
			(start -0.7874 -0.4064)
			(end -0.7874 0.4064)
			(stroke
				(width 0.1524)
				(type default)
			)
			(layer "B.SilkS")
		)
		(fp_line
			(start 0.7874 0.4064)
			(end 0.7874 -0.4064)
			(stroke
				(width 0.1524)
				(type default)
			)
			(layer "B.SilkS")
		)
		(fp_line
			(start -0.7874 0.4064)
			(end 0.7874 0.4064)
			(stroke
				(width 0.1524)
				(type default)
			)
			(layer "B.SilkS")
		)
		(fp_line
			(start 0.67945 -0.305054)
			(end 0.12065 -0.305054)
			(stroke
				(width 0.1)
				(type default)
			)
			(layer "B.Fab")
		)
		(fp_line
			(start 0.12065 -0.305054)
			(end 0.12065 -0.2794)
			(stroke
				(width 0.1)
				(type default)
			)
			(layer "B.Fab")
		)
		(fp_line
			(start -0.12065 -0.3048)
			(end -0.67945 -0.3048)
			(stroke
				(width 0.1)
				(type default)
			)
			(layer "B.Fab")
		)
		(fp_line
			(start -0.67945 -0.3048)
			(end -0.67945 0.3048)
			(stroke
				(width 0.1)
				(type default)
			)
			(layer "B.Fab")
		)
		(fp_line
			(start 0.12065 -0.2794)
			(end -0.12065 -0.2794)
			(stroke
				(width 0.1)
				(type default)
			)
			(layer "B.Fab")
		)
		(fp_line
			(start -0.12065 -0.2794)
			(end -0.12065 -0.3048)
			(stroke
				(width 0.1)
				(type default)
			)
			(layer "B.Fab")
		)
		(fp_line
			(start 0.12065 0.2794)
			(end 0.12065 0.3048)
			(stroke
				(width 0.1)
				(type default)
			)
			(layer "B.Fab")
		)
		(fp_line
			(start -0.120396 0.2794)
			(end 0.12065 0.2794)
			(stroke
				(width 0.1)
				(type default)
			)
			(layer "B.Fab")
		)
		(fp_line
			(start 0.67945 0.3048)
			(end 0.67945 -0.305054)
			(stroke
				(width 0.1)
				(type default)
			)
			(layer "B.Fab")
		)
		(fp_line
			(start 0.12065 0.3048)
			(end 0.67945 0.3048)
			(stroke
				(width 0.1)
				(type default)
			)
			(layer "B.Fab")
		)
		(fp_line
			(start -0.120396 0.3048)
			(end -0.120396 0.2794)
			(stroke
				(width 0.1)
				(type default)
			)
			(layer "B.Fab")
		)
		(fp_line
			(start -0.67945 0.3048)
			(end -0.120396 0.3048)
			(stroke
				(width 0.1)
				(type default)
			)
			(layer "B.Fab")
		)
		(pad "1" smd circle
			(at 0.40005 0 270)
			(size 0 0)
			(layers "B.Cu" "B.Mask" "B.Paste")
			(net "FM_XTAL_INPUT_FREQUENCY_0_MGPIO")
		)
		(pad "2" smd circle
			(at -0.40005 0 270)
			(size 0 0)
			(layers "B.Cu" "B.Mask" "B.Paste")
			(net "GND")
		)
	)
	(footprint ""
		(layer "B.Cu")
		(at 127.7874 -21.003768 90)
		(property "Reference" "R4288"
			(at 0 0 90)
			(layer "B.SilkS")
			(hide yes)
			(effects
				(font
					(size 1.27 1.27)
				)
				(justify mirror)
			)
		)
		(property "Value" ""
			(at 0 0 90)
			(layer "B.Fab")
			(effects
				(font
					(size 1.27 1.27)
				)
				(justify mirror)
			)
		)
		(duplicate_pad_numbers_are_jumpers no)
		(fp_line
			(start 0.7874 -0.4064)
			(end -0.7874 -0.4064)
			(stroke
				(width 0.1524)
				(type default)
			)
			(layer "B.SilkS")
		)
		(fp_line
			(start -0.7874 -0.4064)
			(end -0.7874 0.4064)
			(stroke
				(width 0.1524)
				(type default)
			)
			(layer "B.SilkS")
		)
		(fp_line
			(start 0.7874 0.4064)
			(end 0.7874 -0.4064)
			(stroke
				(width 0.1524)
				(type default)
			)
			(layer "B.SilkS")
		)
		(fp_line
			(start -0.7874 0.4064)
			(end 0.7874 0.4064)
			(stroke
				(width 0.1524)
				(type default)
			)
			(layer "B.SilkS")
		)
		(fp_line
			(start 0.67945 -0.305054)
			(end 0.12065 -0.305054)
			(stroke
				(width 0.1)
				(type default)
			)
			(layer "B.Fab")
		)
		(fp_line
			(start 0.12065 -0.305054)
			(end 0.12065 -0.2794)
			(stroke
				(width 0.1)
				(type default)
			)
			(layer "B.Fab")
		)
		(fp_line
			(start -0.12065 -0.3048)
			(end -0.67945 -0.3048)
			(stroke
				(width 0.1)
				(type default)
			)
			(layer "B.Fab")
		)
		(fp_line
			(start -0.67945 -0.3048)
			(end -0.67945 0.3048)
			(stroke
				(width 0.1)
				(type default)
			)
			(layer "B.Fab")
		)
		(fp_line
			(start 0.12065 -0.2794)
			(end -0.12065 -0.2794)
			(stroke
				(width 0.1)
				(type default)
			)
			(layer "B.Fab")
		)
		(fp_line
			(start -0.12065 -0.2794)
			(end -0.12065 -0.3048)
			(stroke
				(width 0.1)
				(type default)
			)
			(layer "B.Fab")
		)
		(fp_line
			(start 0.12065 0.2794)
			(end 0.12065 0.3048)
			(stroke
				(width 0.1)
				(type default)
			)
			(layer "B.Fab")
		)
		(fp_line
			(start -0.120396 0.2794)
			(end 0.12065 0.2794)
			(stroke
				(width 0.1)
				(type default)
			)
			(layer "B.Fab")
		)
		(fp_line
			(start 0.67945 0.3048)
			(end 0.67945 -0.305054)
			(stroke
				(width 0.1)
				(type default)
			)
			(layer "B.Fab")
		)
		(fp_line
			(start 0.12065 0.3048)
			(end 0.67945 0.3048)
			(stroke
				(width 0.1)
				(type default)
			)
			(layer "B.Fab")
		)
		(fp_line
			(start -0.120396 0.3048)
			(end -0.120396 0.2794)
			(stroke
				(width 0.1)
				(type default)
			)
			(layer "B.Fab")
		)
		(fp_line
			(start -0.67945 0.3048)
			(end -0.120396 0.3048)
			(stroke
				(width 0.1)
				(type default)
			)
			(layer "B.Fab")
		)
		(pad "1" smd circle
			(at 0.40005 0 270)
			(size 0 0)
			(layers "B.Cu" "B.Mask" "B.Paste")
			(net "FM_USB3_1_SWA")
		)
		(pad "2" smd circle
			(at -0.40005 0 270)
			(size 0 0)
			(layers "B.Cu" "B.Mask" "B.Paste")
			(net "GND")
		)
	)
)
